FILE_TYPE = CONNECTIVITY;
{Allegro Design Entry HDL 16.6-p007 (v16-6-112F) 10/10/2012}
"PAGE_NUMBER" = 132;
0"NC";
1"PVNN_PCH_STBY\g";
2"GND\g";
3"PVNN_PCH_STBY\g";
4"GND\g";
5"PVNN_PCH_STBY\g";
6"GND\g";
7"PVNN_PCH_STBY\g";
8"GND\g";
9"GND\g";
10"GND\g";
11"PVNN_PCH_STBY\g";
12"GND\g";
13"PVNN_PCH_STBY\g";
14"PVNN_PCH_STBY\g";
15"PVNN_PCH_STBY\g";
16"GND\g";
%"CAP_A"
"1","(2575,4475)","0","dev_discrete","I1";
;
LOCATION"C3L25"
PART_NUMBER"E15431-004"
VALUE"22.0UF"
TOLERANCE"20%"
PACK_TYPE"0603V"
VOLTAGE"4V"
MATERIAL"X6S"
CDS_LOCATION"C3L25"
BOM_COST"SB"
CDS_LIB"dev_discrete"
CDS_SEC"1"
$SEC"1"
ROOM"SB_DECOUPLING";
"B"
$PN"2"2;
"A"
$PN"1"13;
%"GND"
"1","(2050,4150)","0","mstr_symbols","I10";
;
VOLTAGE"0.0V"
BOM_COST"SB"
SIZE"1B"
CDS_LIB"mstr_symbols"
ROOM"SB_DECOUPLING"
BODY_TYPE"PLUMBING"
HDL_POWER"GND";
"A\NAC"2;
%"CAP_A"
"1","(2200,3500)","0","dev_discrete","I11";
;
LOCATION"C7A36"
PART_NUMBER"E15431-004"
VALUE"22.0UF"
TOLERANCE"20%"
PACK_TYPE"0603V"
VOLTAGE"4V"
MATERIAL"X6S"
CDS_LOCATION"C7A36"
BOM_COST"SB"
CDS_LIB"dev_discrete"
CDS_SEC"1"
$SEC"1"
ROOM"SB_DECOUPLING";
"B"
$PN"2"4;
"A"
$PN"1"3;
%"CAP_A"
"1","(1825,3500)","0","dev_discrete","I12";
;
LOCATION"C3N12"
VALUE"22.0UF"
TOLERANCE"20%"
PACK_TYPE"0603V"
VOLTAGE"4V"
MATERIAL"X6S"
PART_NUMBER"E15431-004"
CDS_LOCATION"C3N12"
BOM_COST"SB"
CDS_LIB"dev_discrete"
CDS_SEC"1"
$SEC"1"
ROOM"SB_DECOUPLING";
"B"
$PN"2"4;
"A"
$PN"1"3;
%"CAP_A"
"1","(1450,3500)","0","dev_discrete","I13";
;
PART_NUMBER"E15431-004"
VALUE"22.0UF"
TOLERANCE"20%"
PACK_TYPE"0603V"
VOLTAGE"4V"
MATERIAL"X6S"
LOCATION"C3N10"
CDS_LOCATION"C3N10"
BOM_COST"SB"
CDS_LIB"dev_discrete"
CDS_SEC"1"
$SEC"1"
ROOM"SB_DECOUPLING";
"B"
$PN"2"4;
"A"
$PN"1"3;
%"PVNN_PCH_STBY"
"1","(1350,3750)","0","mstr_symbols","I14";
;
VOLTAGE"1.0V"
CDS_LIB"mstr_symbols"
BOM_COST"SB"
ROOM"SB_DECOUPLING"
BODY_TYPE"PLUMBING"
HDL_POWER"PVNN_PCH_STBY";
"G\NAC"3;
%"GND"
"1","(2075,3175)","0","mstr_symbols","I15";
;
VOLTAGE"0"
CDS_LIB"mstr_symbols"
SIZE"1B"
BOM_COST"SB"
ROOM"SB_DECOUPLING"
BODY_TYPE"PLUMBING"
HDL_POWER"GND";
"A\NAC"4;
%"CAP_A"
"1","(1850,2525)","0","dev_discrete","I16";
;
LOCATION"C3N24"
PART_NUMBER"E15431-004"
VALUE"22.0UF"
TOLERANCE"20%"
PACK_TYPE"0603V"
VOLTAGE"4V"
MATERIAL"X6S"
CDS_LOCATION"C3N24"
BOM_COST"SB"
CDS_LIB"dev_discrete"
CDS_SEC"1"
$SEC"1"
ROOM"SB_DECOUPLING";
"B"
$PN"2"6;
"A"
$PN"1"5;
%"CAP_A"
"1","(1475,2525)","0","dev_discrete","I17";
;
LOCATION"C3N28"
PART_NUMBER"E15431-004"
VALUE"22.0UF"
TOLERANCE"20%"
PACK_TYPE"0603V"
VOLTAGE"4V"
MATERIAL"X6S"
CDS_LOCATION"C3N28"
BOM_COST"SB"
CDS_LIB"dev_discrete"
CDS_SEC"1"
$SEC"1"
ROOM"SB_DECOUPLING";
"B"
$PN"2"6;
"A"
$PN"1"5;
%"PVNN_PCH_STBY"
"1","(1400,2775)","0","mstr_symbols","I18";
;
VOLTAGE"1.0V"
CDS_LIB"mstr_symbols"
BOM_COST"SB"
ROOM"SB_DECOUPLING"
BODY_TYPE"PLUMBING"
HDL_POWER"PVNN_PCH_STBY";
"G\NAC"5;
%"CAP_A"
"1","(1075,3500)","0","dev_discrete","I19";
;
LOCATION"C3N11"
PART_NUMBER"E15431-004"
VALUE"22.0UF"
TOLERANCE"20%"
PACK_TYPE"0603V"
VOLTAGE"4V"
MATERIAL"X6S"
CDS_LOCATION"C3N11"
BOM_COST"SB"
CDS_LIB"dev_discrete"
CDS_SEC"1"
$SEC"1"
ROOM"SB_DECOUPLING";
"B"
$PN"2"4;
"A"
$PN"1"3;
%"CAP_A"
"1","(2200,4475)","0","dev_discrete","I2";
;
LOCATION"C3M7"
PART_NUMBER"E15431-004"
VALUE"22.0UF"
TOLERANCE"20%"
PACK_TYPE"0603V"
VOLTAGE"4V"
MATERIAL"X6S"
CDS_LOCATION"C3M7"
BOM_COST"SB"
CDS_LIB"dev_discrete"
CDS_SEC"1"
$SEC"1"
ROOM"SB_DECOUPLING";
"B"
$PN"2"2;
"A"
$PN"1"13;
%"CAP_A"
"1","(1100,2525)","0","dev_discrete","I20";
;
LOCATION"C3N31"
PART_NUMBER"E15431-004"
VALUE"22.0UF"
TOLERANCE"20%"
PACK_TYPE"0603V"
VOLTAGE"4V"
MATERIAL"X6S"
CDS_LOCATION"C3N31"
BOM_COST"SB"
CDS_LIB"dev_discrete"
CDS_SEC"1"
$SEC"1"
ROOM"SB_DECOUPLING";
"B"
$PN"2"6;
"A"
$PN"1"5;
%"GND"
"1","(2050,2200)","0","mstr_symbols","I21";
;
VOLTAGE"0"
BOM_COST"SB"
CDS_LIB"mstr_symbols"
SIZE"1B"
ROOM"SB_DECOUPLING"
BODY_TYPE"PLUMBING"
HDL_POWER"GND";
"A\NAC"6;
%"PVNN_PCH_STBY"
"1","(1925,1875)","0","mstr_symbols","I22";
;
VOLTAGE"1.0V"
CDS_LIB"mstr_symbols"
BOM_COST"SB"
ROOM"SB_DECOUPLING"
BODY_TYPE"PLUMBING"
HDL_POWER"PVNN_PCH_STBY";
"G\NAC"7;
%"CAP"
"1","(2150,1575)","0","mstr_discrete","I23";
;
LOCATION"C7A33"
PART_NUMBER"C95333-006"
VALUE"47UF"
TOLERANCE"20%"
PACK_TYPE"0805"
VOLTAGE"4V"
MATERIAL"X6S"
CDS_LIB"mstr_discrete"
BOM_COST"SB"
CDS_SEC"1"
$SEC"1"
CDS_LOCATION"C7A33"
ROOM"SB_DECOUPLING";
"A"
$PN"1"7;
"B"
$PN"2"8;
%"CAP"
"1","(1700,1575)","0","mstr_discrete","I24";
;
LOCATION"C7B4"
PART_NUMBER"C95333-006"
VALUE"47UF"
TOLERANCE"20%"
PACK_TYPE"0805"
VOLTAGE"4V"
MATERIAL"X6S"
CDS_LIB"mstr_discrete"
BOM_COST"SB"
CDS_SEC"1"
$SEC"1"
CDS_LOCATION"C7B4"
ROOM"SB_DECOUPLING";
"A"
$PN"1"7;
"B"
$PN"2"8;
%"GND"
"1","(1925,1200)","0","mstr_symbols","I25";
;
VOLTAGE"0.0V"
BOM_COST"SB"
CDS_LIB"mstr_symbols"
SIZE"1B"
ROOM"SB_DECOUPLING"
BODY_TYPE"PLUMBING"
HDL_POWER"GND";
"A\NAC"8;
%"CAP_A"
"1","(-325,4050)","0","dev_discrete","I26";
;
LOCATION"C2N9"
PART_NUMBER"D97712-004"
VALUE"1.0UF"
TOLERANCE"10%"
PACK_TYPE"0402V"
VOLTAGE"6.3V"
MATERIAL"X6S"
CDS_LOCATION"C2N9"
CDS_LIB"dev_discrete"
CDS_SEC"1"
$SEC"1"
ROOM"SB_DECOUPLING";
"B"
$PN"2"9;
"A"
$PN"1"1;
%"CAP_A"
"1","(-725,4050)","0","dev_discrete","I27";
;
LOCATION"C2N3"
PART_NUMBER"D97712-004"
VALUE"1.0UF"
TOLERANCE"10%"
PACK_TYPE"0402V"
VOLTAGE"6.3V"
MATERIAL"X6S"
CDS_LOCATION"C2N3"
BOM_COST"SB"
CDS_LIB"dev_discrete"
CDS_SEC"1"
$SEC"1"
ROOM"SB_DECOUPLING";
"B"
$PN"2"9;
"A"
$PN"1"1;
%"CAP_A"
"1","(-300,3025)","0","dev_discrete","I28";
;
LOCATION"C2N4"
PART_NUMBER"D97712-004"
VALUE"1.0UF"
TOLERANCE"10%"
PACK_TYPE"0402V"
VOLTAGE"6.3V"
MATERIAL"X6S"
CDS_LOCATION"C2N4"
CDS_LIB"dev_discrete"
CDS_SEC"1"
$SEC"1"
ROOM"SB_DECOUPLING";
"B"
$PN"2"10;
"A"
$PN"1"14;
%"CAP_A"
"1","(-700,3025)","0","dev_discrete","I29";
;
LOCATION"C2N12"
PART_NUMBER"D97712-004"
VALUE"1.0UF"
TOLERANCE"10%"
PACK_TYPE"0402V"
VOLTAGE"6.3V"
MATERIAL"X6S"
CDS_LOCATION"C2N12"
BOM_COST"SB"
CDS_LIB"dev_discrete"
CDS_SEC"1"
$SEC"1"
ROOM"SB_DECOUPLING";
"B"
$PN"2"10;
"A"
$PN"1"14;
%"CAP_A"
"1","(1825,4475)","0","dev_discrete","I3";
;
LOCATION"C3L26"
PART_NUMBER"E15431-004"
VALUE"22.0UF"
TOLERANCE"20%"
PACK_TYPE"0603V"
VOLTAGE"4V"
MATERIAL"X6S"
CDS_LOCATION"C3L26"
BOM_COST"SB"
CDS_LIB"dev_discrete"
CDS_SEC"1"
$SEC"1"
ROOM"SB_DECOUPLING";
"B"
$PN"2"2;
"A"
$PN"1"13;
%"CAP_A"
"1","(-1100,4050)","0","dev_discrete","I30";
;
LOCATION"C2N11"
PART_NUMBER"D97712-004"
VALUE"1.0UF"
TOLERANCE"10%"
VOLTAGE"6.3V"
MATERIAL"X6S"
PACK_TYPE"0402V"
CDS_LOCATION"C2N11"
BOM_COST"SB"
CDS_LIB"dev_discrete"
CDS_SEC"1"
$SEC"1"
ROOM"SB_DECOUPLING";
"B"
$PN"2"9;
"A"
$PN"1"1;
%"CAP_A"
"1","(-1475,4050)","0","dev_discrete","I31";
;
PART_NUMBER"D97712-004"
VALUE"1.0UF"
TOLERANCE"10%"
PACK_TYPE"0402V"
VOLTAGE"6.3V"
MATERIAL"X6S"
LOCATION"C3N19"
CDS_LOCATION"C3N19"
BOM_COST"SB"
CDS_LIB"dev_discrete"
CDS_SEC"1"
$SEC"1"
ROOM"SB_DECOUPLING";
"B"
$PN"2"9;
"A"
$PN"1"1;
%"CAP_A"
"1","(-1850,4050)","0","dev_discrete","I32";
;
LOCATION"C3N3"
PART_NUMBER"D97712-004"
VALUE"1.0UF"
TOLERANCE"10%"
PACK_TYPE"0402V"
VOLTAGE"6.3V"
MATERIAL"X6S"
CDS_LOCATION"C3N3"
BOM_COST"SB"
CDS_LIB"dev_discrete"
CDS_SEC"1"
$SEC"1"
ROOM"SB_DECOUPLING";
"B"
$PN"2"9;
"A"
$PN"1"1;
%"GND"
"1","(-1750,3750)","0","mstr_symbols","I33";
;
VOLTAGE"0"
SIZE"1B"
CDS_LIB"mstr_symbols"
BOM_COST"SB"
ROOM"SB_DECOUPLING"
BODY_TYPE"PLUMBING"
HDL_POWER"GND";
"A\NAC"9;
%"CAP_A"
"1","(-1075,3025)","0","dev_discrete","I34";
;
PART_NUMBER"D97712-004"
TOLERANCE"10%"
PACK_TYPE"0402V"
VOLTAGE"6.3V"
MATERIAL"X6S"
LOCATION"C3N1"
VALUE"1.0UF"
CDS_LOCATION"C3N1"
BOM_COST"SB"
CDS_LIB"dev_discrete"
CDS_SEC"1"
$SEC"1"
ROOM"SB_DECOUPLING";
"B"
$PN"2"10;
"A"
$PN"1"14;
%"CAP_A"
"1","(-1450,3025)","0","dev_discrete","I35";
;
LOCATION"C3N7"
PART_NUMBER"D97712-004"
VALUE"1.0UF"
TOLERANCE"10%"
PACK_TYPE"0402V"
VOLTAGE"6.3V"
MATERIAL"X6S"
CDS_LOCATION"C3N7"
BOM_COST"SB"
CDS_LIB"dev_discrete"
CDS_SEC"1"
$SEC"1"
ROOM"SB_DECOUPLING";
"B"
$PN"2"10;
"A"
$PN"1"14;
%"CAP_A"
"1","(-1825,3025)","0","dev_discrete","I36";
;
LOCATION"C3N16"
PART_NUMBER"D97712-004"
VALUE"1.0UF"
TOLERANCE"10%"
PACK_TYPE"0402V"
VOLTAGE"6.3V"
MATERIAL"X6S"
CDS_LOCATION"C3N16"
BOM_COST"SB"
CDS_LIB"dev_discrete"
CDS_SEC"1"
$SEC"1"
ROOM"SB_DECOUPLING";
"B"
$PN"2"10;
"A"
$PN"1"14;
%"GND"
"1","(-1725,2725)","0","mstr_symbols","I37";
;
VOLTAGE"0"
SIZE"1B"
CDS_LIB"mstr_symbols"
BOM_COST"SB"
ROOM"SB_DECOUPLING"
BODY_TYPE"PLUMBING"
HDL_POWER"GND";
"A\NAC"10;
%"CAP"
"1","(-650,1900)","0","mstr_discrete","I38";
;
LOCATION"C7A32"
PART_NUMBER"C95333-006"
VALUE"47UF"
TOLERANCE"20%"
PACK_TYPE"0805"
VOLTAGE"4V"
MATERIAL"X6S"
CDS_LIB"mstr_discrete"
BOM_COST"SB"
CDS_SEC"1"
$SEC"1"
CDS_LOCATION"C7A32"
ROOM"SB_DECOUPLING";
"A"
$PN"1"11;
"B"
$PN"2"12;
%"PVNN_PCH_STBY"
"1","(-875,2200)","0","mstr_symbols","I39";
;
VOLTAGE"1.0V"
CDS_LIB"mstr_symbols"
BOM_COST"SB"
ROOM"SB_DECOUPLING"
BODY_TYPE"PLUMBING"
HDL_POWER"PVNN_PCH_STBY";
"G\NAC"11;
%"CAP_A"
"1","(1450,4475)","0","dev_discrete","I4";
;
LOCATION"C3L27"
PART_NUMBER"E15431-004"
VALUE"22.0UF"
TOLERANCE"20%"
PACK_TYPE"0603V"
VOLTAGE"4V"
MATERIAL"X6S"
CDS_LOCATION"C3L27"
BOM_COST"SB"
CDS_LIB"dev_discrete"
CDS_SEC"1"
$SEC"1"
ROOM"SB_DECOUPLING";
"B"
$PN"2"2;
"A"
$PN"1"13;
%"CAP"
"1","(-1100,1900)","0","mstr_discrete","I40";
;
LOCATION"C7A31"
PART_NUMBER"C95333-006"
VALUE"47UF"
TOLERANCE"20%"
PACK_TYPE"0805"
VOLTAGE"4V"
MATERIAL"X6S"
CDS_LIB"mstr_discrete"
BOM_COST"SB"
CDS_SEC"1"
$SEC"1"
CDS_LOCATION"C7A31"
ROOM"SB_DECOUPLING";
"A"
$PN"1"11;
"B"
$PN"2"12;
%"GND"
"1","(-875,1525)","0","mstr_symbols","I41";
;
VOLTAGE"0.0V"
SIZE"1B"
CDS_LIB"mstr_symbols"
BOM_COST"SB"
ROOM"SB_DECOUPLING"
BODY_TYPE"PLUMBING"
HDL_POWER"GND";
"A\NAC"12;
%"CAP_A"
"1","(-2225,4050)","0","dev_discrete","I42";
;
LOCATION"C3N18"
PART_NUMBER"D97712-004"
VALUE"1.0UF"
TOLERANCE"10%"
PACK_TYPE"0402V"
VOLTAGE"6.3V"
MATERIAL"X6S"
CDS_LOCATION"C3N18"
BOM_COST"SB"
CDS_LIB"dev_discrete"
CDS_SEC"1"
$SEC"1"
ROOM"SB_DECOUPLING";
"B"
$PN"2"9;
"A"
$PN"1"1;
%"CAP_A"
"1","(-2625,4050)","0","dev_discrete","I43";
;
LOCATION"C3N2"
PART_NUMBER"D97712-004"
VALUE"1.0UF"
TOLERANCE"10%"
PACK_TYPE"0402V"
VOLTAGE"6.3V"
MATERIAL"X6S"
CDS_LOCATION"C3N2"
BOM_COST"SB"
CDS_LIB"dev_discrete"
CDS_SEC"1"
$SEC"1"
ROOM"SB_DECOUPLING";
"B"
$PN"2"9;
"A"
$PN"1"1;
%"CAP_A"
"1","(-2200,3025)","0","dev_discrete","I44";
;
LOCATION"C3N6"
PART_NUMBER"D97712-004"
VALUE"1.0UF"
TOLERANCE"10%"
PACK_TYPE"0402V"
VOLTAGE"6.3V"
MATERIAL"X6S"
CDS_LOCATION"C3N6"
BOM_COST"SB"
CDS_LIB"dev_discrete"
CDS_SEC"1"
$SEC"1"
ROOM"SB_DECOUPLING";
"B"
$PN"2"10;
"A"
$PN"1"14;
%"CAP_A"
"1","(-2600,3025)","0","dev_discrete","I45";
;
LOCATION"C3N17"
PART_NUMBER"D97712-004"
VALUE"1.0UF"
TOLERANCE"10%"
PACK_TYPE"0402V"
VOLTAGE"6.3V"
MATERIAL"X6S"
CDS_LOCATION"C3N17"
BOM_COST"SB"
CDS_LIB"dev_discrete"
CDS_SEC"1"
$SEC"1"
ROOM"SB_DECOUPLING";
"B"
$PN"2"10;
"A"
$PN"1"14;
%"CAP_A"
"1","(-3000,4050)","0","dev_discrete","I46";
;
PART_NUMBER"D97712-004"
LOCATION"C3N4"
VALUE"1.0UF"
TOLERANCE"10%"
PACK_TYPE"0402V"
VOLTAGE"6.3V"
MATERIAL"X6S"
CDS_LOCATION"C3N4"
BOM_COST"SB"
CDS_LIB"dev_discrete"
CDS_SEC"1"
$SEC"1"
ROOM"SB_DECOUPLING";
"B"
$PN"2"9;
"A"
$PN"1"1;
%"PVNN_PCH_STBY"
"1","(-3225,4300)","0","mstr_symbols","I47";
;
VOLTAGE"1.0V"
CDS_LIB"mstr_symbols"
BOM_COST"SB"
ROOM"SB_DECOUPLING"
BODY_TYPE"PLUMBING"
HDL_POWER"PVNN_PCH_STBY";
"G\NAC"1;
%"CAP_A"
"1","(-3400,4050)","0","dev_discrete","I48";
;
LOCATION"C3N5"
PART_NUMBER"D97712-004"
VALUE"1.0UF"
TOLERANCE"10%"
PACK_TYPE"0402V"
VOLTAGE"6.3V"
MATERIAL"X6S"
CDS_LOCATION"C3N5"
BOM_COST"SB"
CDS_LIB"dev_discrete"
CDS_SEC"1"
$SEC"1"
ROOM"SB_DECOUPLING";
"B"
$PN"2"9;
"A"
$PN"1"1;
%"CAP_A"
"1","(-2975,3025)","0","dev_discrete","I49";
;
LOCATION"C3N15"
PART_NUMBER"D97712-004"
VALUE"1.0UF"
TOLERANCE"10%"
PACK_TYPE"0402V"
VOLTAGE"6.3V"
MATERIAL"X6S"
CDS_LOCATION"C3N15"
BOM_COST"SB"
CDS_LIB"dev_discrete"
CDS_SEC"1"
$SEC"1"
ROOM"SB_DECOUPLING";
"B"
$PN"2"10;
"A"
$PN"1"14;
%"PVNN_PCH_STBY"
"1","(1350,4725)","0","mstr_symbols","I5";
;
VOLTAGE"1.0V"
CDS_LIB"mstr_symbols"
BOM_COST"SB"
ROOM"SB_DECOUPLING"
BODY_TYPE"PLUMBING"
HDL_POWER"PVNN_PCH_STBY";
"G\NAC"13;
%"PVNN_PCH_STBY"
"1","(-3200,3275)","0","mstr_symbols","I50";
;
VOLTAGE"1.0V"
CDS_LIB"mstr_symbols"
BOM_COST"SB"
ROOM"SB_DECOUPLING"
BODY_TYPE"PLUMBING"
HDL_POWER"PVNN_PCH_STBY";
"G\NAC"14;
%"CAP_A"
"1","(-3375,3025)","0","dev_discrete","I51";
;
LOCATION"C3N20"
PART_NUMBER"D97712-004"
VALUE"1.0UF"
TOLERANCE"10%"
PACK_TYPE"0402V"
VOLTAGE"6.3V"
MATERIAL"X6S"
CDS_LOCATION"C3N20"
BOM_COST"SB"
CDS_LIB"dev_discrete"
CDS_SEC"1"
$SEC"1"
ROOM"SB_DECOUPLING";
"B"
$PN"2"10;
"A"
$PN"1"14;
%"CAP_A"
"1","(-2550,1925)","0","dev_discrete","I52";
;
LOCATION"C3L23"
PART_NUMBER"E15431-004"
VALUE"22.0UF"
TOLERANCE"20%"
PACK_TYPE"0603V"
VOLTAGE"4V"
MATERIAL"X6S"
CDS_LOCATION"C3L23"
BOM_COST"SB"
CDS_LIB"dev_discrete"
CDS_SEC"1"
$SEC"1"
ROOM"SB_DECOUPLING";
"B"
$PN"2"16;
"A"
$PN"1"15;
%"PVNN_PCH_STBY"
"1","(-3150,2200)","0","mstr_symbols","I53";
;
VOLTAGE"1.0V"
CDS_LIB"mstr_symbols"
BOM_COST"SB"
ROOM"SB_DECOUPLING"
BODY_TYPE"PLUMBING"
HDL_POWER"PVNN_PCH_STBY";
"G\NAC"15;
%"CAP_A"
"1","(-2950,1925)","0","dev_discrete","I54";
;
LOCATION"C3L22"
PART_NUMBER"E15431-004"
VALUE"22.0UF"
TOLERANCE"20%"
PACK_TYPE"0603V"
VOLTAGE"4V"
MATERIAL"X6S"
CDS_LOCATION"C3L22"
BOM_COST"SB"
CDS_LIB"dev_discrete"
CDS_SEC"1"
$SEC"1"
ROOM"SB_DECOUPLING";
"B"
$PN"2"16;
"A"
$PN"1"15;
%"GND"
"1","(-3100,1600)","0","mstr_symbols","I55";
;
VOLTAGE"0.0V"
CDS_LIB"mstr_symbols"
SIZE"1B"
BOM_COST"SB"
ROOM"SB_DECOUPLING"
BODY_TYPE"PLUMBING"
HDL_POWER"GND";
"A\NAC"16;
%"CAP_A"
"1","(-3425,1925)","0","dev_discrete","I56";
;
LOCATION"C3L24"
PART_NUMBER"E15431-004"
VALUE"22.0UF"
TOLERANCE"20%"
PACK_TYPE"0603V"
VOLTAGE"4V"
MATERIAL"X6S"
CDS_LOCATION"C3L24"
BOM_COST"SB"
CDS_LIB"dev_discrete"
CDS_SEC"1"
$SEC"1"
ROOM"SB_DECOUPLING";
"B"
$PN"2"16;
"A"
$PN"1"15;
%"CAP_A"
"1","(1075,4475)","0","dev_discrete","I6";
;
LOCATION"C3M6"
PART_NUMBER"E15431-004"
VALUE"22.0UF"
TOLERANCE"20%"
PACK_TYPE"0603V"
VOLTAGE"4V"
MATERIAL"X6S"
CDS_LOCATION"C3M6"
BOM_COST"SB"
CDS_LIB"dev_discrete"
CDS_SEC"1"
$SEC"1"
ROOM"SB_DECOUPLING";
"B"
$PN"2"2;
"A"
$PN"1"13;
%"CAP_A"
"1","(2550,3500)","0","dev_discrete","I7";
;
LOCATION"C7C9"
PART_NUMBER"E15431-004"
VALUE"22.0UF"
TOLERANCE"20%"
PACK_TYPE"0603V"
VOLTAGE"4V"
MATERIAL"X6S"
CDS_LOCATION"C7C9"
BOM_COST"SB"
CDS_LIB"dev_discrete"
CDS_SEC"1"
$SEC"1"
ROOM"SB_DECOUPLING";
"B"
$PN"2"4;
"A"
$PN"1"3;
%"CAP_A"
"1","(2600,2525)","0","dev_discrete","I8";
;
LOCATION"C3N27"
PART_NUMBER"E15431-004"
VALUE"22.0UF"
TOLERANCE"20%"
PACK_TYPE"0603V"
VOLTAGE"4V"
MATERIAL"X6S"
CDS_LOCATION"C3N27"
BOM_COST"SB"
CDS_LIB"dev_discrete"
CDS_SEC"1"
$SEC"1"
ROOM"SB_DECOUPLING";
"B"
$PN"2"6;
"A"
$PN"1"5;
%"CAP_A"
"1","(2225,2525)","0","dev_discrete","I9";
;
LOCATION"C3N30"
PART_NUMBER"E15431-004"
VALUE"22.0UF"
TOLERANCE"20%"
VOLTAGE"4V"
MATERIAL"X6S"
PACK_TYPE"0603V"
CDS_LOCATION"C3N30"
BOM_COST"SB"
CDS_LIB"dev_discrete"
CDS_SEC"1"
$SEC"1"
ROOM"SB_DECOUPLING";
"B"
$PN"2"6;
"A"
$PN"1"5;
END.
